(kicad_pcb
	(version 20260206)
	(generator "pcbnew")
	(generator_version "10.0")
	(general
		(thickness 1.6)
		(legacy_teardrops no)
	)
	(paper "A4")
	(title_block
		(title "Wiwynn_Tioga_Pass_MB.brd")
		(comment 1 "Tioga Pass / footprints 1986-1992 of 4770")
	)
	(layers
		(0 "F.Cu" signal "TOP")
		(4 "In1.Cu" signal "L2GND")
		(6 "In2.Cu" signal "L3")
		(8 "In3.Cu" signal "L4GND")
		(10 "In4.Cu" signal "L5")
		(12 "In5.Cu" signal "L6GND")
		(14 "In6.Cu" signal "L7VCC")
		(16 "In7.Cu" signal "L8VCC")
		(18 "In8.Cu" signal "L9GND")
		(20 "In9.Cu" signal "L10")
		(22 "In10.Cu" signal "L11GND")
		(24 "In11.Cu" signal "L12")
		(26 "In12.Cu" signal "L13GND")
		(2 "B.Cu" signal "BOTTOM")
		(9 "F.Adhes" user "F.Adhesive")
		(11 "B.Adhes" user "B.Adhesive")
		(13 "F.Paste" user "Package Geometry/Pastemask Top")
		(15 "B.Paste" user "Package Geometry/Pastemask Bottom")
		(5 "F.SilkS" user "Ref Des/Silkscreen Top")
		(7 "B.SilkS" user "Ref Des/Silkscreen Bottom")
		(1 "F.Mask" user "Board Geometry/Soldermask Top")
		(3 "B.Mask" user "Board Geometry/Soldermask Bottom")
		(17 "Dwgs.User" user "User.Drawings")
		(19 "Cmts.User" user "User.Comments")
		(21 "Eco1.User" user "User.Eco1")
		(23 "Eco2.User" user "User.Eco2")
		(25 "Edge.Cuts" user "Board Geometry/Outline")
		(27 "Margin" user)
		(31 "F.CrtYd" user "Package Geometry/Place Bound Top")
		(29 "B.CrtYd" user "Package Geometry/Place Bound Bottom")
		(35 "F.Fab" user "Ref Des/Assembly Top")
		(33 "B.Fab" user "Ref Des/Assembly Bottom")
	)
	(footprint ""
		(layer "F.Cu")
		(at 351.410524 -4.296918 180)
		(property "Reference" "RT33"
			(at 1.01473 0.656336 90)
			(unlocked yes)
			(layer "F.SilkS")
			(effects
				(font
					(size 0.4064 0.254)
					(thickness 0.1524)
				)
			)
		)
		(property "Value" ""
			(at 0 0 180)
			(layer "F.Fab")
			(effects
				(font
					(size 1.27 1.27)
				)
			)
		)
		(duplicate_pad_numbers_are_jumpers no)
		(fp_poly
			(pts
				(xy -0.4953 -0.2032) (xy 0.4953 -0.2032) (xy 0.4953 1.6002) (xy -0.4953 1.6002)
			)
			(stroke
				(width 0)
				(type default)
			)
			(fill no)
			(layer "F.CrtYd")
		)
		(fp_line
			(start 0.4953 1.6002)
			(end -0.4953 1.6002)
			(stroke
				(width 0.1)
				(type default)
			)
			(layer "F.Fab")
		)
		(fp_line
			(start 0.4953 -0.2032)
			(end 0.4953 1.6002)
			(stroke
				(width 0.1)
				(type default)
			)
			(layer "F.Fab")
		)
		(fp_line
			(start -0.4953 1.6002)
			(end -0.4953 -0.2032)
			(stroke
				(width 0.1)
				(type default)
			)
			(layer "F.Fab")
		)
		(fp_line
			(start -0.4953 -0.2032)
			(end 0.4953 -0.2032)
			(stroke
				(width 0.1)
				(type default)
			)
			(layer "F.Fab")
		)
		(pad "1" smd rect
			(at 0 0 180)
			(size 0.762 0.889)
			(layers "F.Cu" "F.Mask" "F.Paste")
			(net "VR_PVDDQ_ABC_PH1_BOOT")
		)
		(pad "2" smd rect
			(at 0 1.397 180)
			(size 0.762 0.889)
			(layers "F.Cu" "F.Mask" "F.Paste")
			(net "VR_PVDDQ_ABC_PH1_BOOT_R")
		)
		(zone
			(layer "F.Cu")
			(hatch none 0.5)
			(connect_pads
				(clearance 0)
			)
			(min_thickness 0.25)
			(keepout
				(tracks allowed)
				(vias not_allowed)
				(pads allowed)
				(copperpour not_allowed)
				(footprints allowed)
			)
			(placement
				(enabled no)
				(sheetname "")
			)
			(fill
				(thermal_gap 0.5)
				(thermal_bridge_width 0.5)
				(island_removal_mode 0)
			)
			(polygon
				(pts
					(xy 351.029524 -5.249418) (xy 351.029524 -4.741418) (xy 351.791524 -4.741418) (xy 351.791524 -5.249418)
				)
			)
		)
		(zone
			(layer "F.Cu")
			(hatch none 0.5)
			(connect_pads
				(clearance 0)
			)
			(min_thickness 0.25)
			(keepout
				(tracks not_allowed)
				(vias allowed)
				(pads allowed)
				(copperpour not_allowed)
				(footprints allowed)
			)
			(placement
				(enabled no)
				(sheetname "")
			)
			(fill
				(thermal_gap 0.5)
				(thermal_bridge_width 0.5)
				(island_removal_mode 0)
			)
			(polygon
				(pts
					(xy 351.791524 -5.249418) (xy 351.029524 -5.249418) (xy 351.029524 -4.741418) (xy 351.791524 -4.741418)
				)
			)
		)
	)
	(footprint ""
		(layer "F.Cu")
		(at 411.6832 -51.308 180)
		(property "Reference" "U8D4"
			(at 1.778 5.09143 0)
			(unlocked yes)
			(layer "F.SilkS")
			(effects
				(font
					(size 0.7874 0.5842)
					(thickness 0.1524)
				)
				(justify left)
			)
		)
		(property "Value" ""
			(at 0 0 180)
			(layer "F.Fab")
			(effects
				(font
					(size 1.27 1.27)
				)
			)
		)
		(duplicate_pad_numbers_are_jumpers no)
		(fp_line
			(start 4.191 4.4069)
			(end 1.2954 4.4069)
			(stroke
				(width 0.1524)
				(type default)
			)
			(layer "F.SilkS")
		)
		(fp_line
			(start 4.191 -0.5969)
			(end 4.191 4.4069)
			(stroke
				(width 0.1524)
				(type default)
			)
			(layer "F.SilkS")
		)
		(fp_line
			(start 3.3782 0.6731)
			(end 3.3782 -0.5842)
			(stroke
				(width 0.1524)
				(type default)
			)
			(layer "F.SilkS")
		)
		(fp_line
			(start 2.1082 0.6731)
			(end 3.3782 0.6731)
			(stroke
				(width 0.1524)
				(type default)
			)
			(layer "F.SilkS")
		)
		(fp_line
			(start 2.1082 -0.5842)
			(end 2.1082 0.6731)
			(stroke
				(width 0.1524)
				(type default)
			)
			(layer "F.SilkS")
		)
		(fp_line
			(start 1.2954 4.4069)
			(end 1.2954 -0.5969)
			(stroke
				(width 0.1524)
				(type default)
			)
			(layer "F.SilkS")
		)
		(fp_line
			(start 1.2954 -0.5969)
			(end 4.191 -0.5969)
			(stroke
				(width 0.1524)
				(type default)
			)
			(layer "F.SilkS")
		)
		(fp_circle
			(center -1.37414 -0.541528)
			(end -1.50114 -0.541528)
			(stroke
				(width 0.254)
				(type default)
			)
			(fill no)
			(layer "F.SilkS")
		)
		(fp_poly
			(pts
				(xy 0.7493 -0.5969) (xy 4.7371 -0.5969) (xy 4.7371 4.4069) (xy 0.7493 4.4069)
			)
			(stroke
				(width 0)
				(type default)
			)
			(fill no)
			(layer "F.CrtYd")
		)
		(fp_line
			(start 4.7371 4.4069)
			(end 0.7493 4.4069)
			(stroke
				(width 0.1)
				(type default)
			)
			(layer "F.Fab")
		)
		(fp_line
			(start 4.7371 -0.5969)
			(end 4.7371 4.4069)
			(stroke
				(width 0.1)
				(type default)
			)
			(layer "F.Fab")
		)
		(fp_line
			(start 3.3782 0.6731)
			(end 3.3782 -0.5842)
			(stroke
				(width 0.1)
				(type default)
			)
			(layer "F.Fab")
		)
		(fp_line
			(start 2.1082 0.6731)
			(end 3.3782 0.6731)
			(stroke
				(width 0.1)
				(type default)
			)
			(layer "F.Fab")
		)
		(fp_line
			(start 2.1082 -0.5842)
			(end 2.1082 0.6731)
			(stroke
				(width 0.1)
				(type default)
			)
			(layer "F.Fab")
		)
		(fp_line
			(start 0.7493 4.4069)
			(end 0.7493 -0.5969)
			(stroke
				(width 0.1)
				(type default)
			)
			(layer "F.Fab")
		)
		(fp_line
			(start 0.7493 -0.5969)
			(end 4.7371 -0.5969)
			(stroke
				(width 0.1)
				(type default)
			)
			(layer "F.Fab")
		)
		(fp_circle
			(center -1.382014 -0.7112)
			(end -1.509014 -0.7112)
			(stroke
				(width 0.254)
				(type default)
			)
			(fill no)
			(layer "F.Fab")
		)
		(pad "1" smd rect
			(at 0 0 180)
			(size 1.9304 0.635)
			(layers "F.Cu" "F.Mask" "F.Paste")
			(net "GND")
		)
		(pad "2" smd rect
			(at 0 1.27 180)
			(size 1.9304 0.635)
			(layers "F.Cu" "F.Mask" "F.Paste")
			(net "GND")
		)
		(pad "3" smd rect
			(at 0 2.54 180)
			(size 1.9304 0.635)
			(layers "F.Cu" "F.Mask" "F.Paste")
			(net "PU_AT24C64_A2")
		)
		(pad "4" smd rect
			(at 0 3.81 180)
			(size 1.9304 0.635)
			(layers "F.Cu" "F.Mask" "F.Paste")
			(net "GND")
		)
		(pad "5" smd rect
			(at 5.4864 3.81 180)
			(size 1.9304 0.635)
			(layers "F.Cu" "F.Mask" "F.Paste")
			(net "SMB_SENSOR_STBY_LVC3_SDA_R2")
		)
		(pad "6" smd rect
			(at 5.4864 2.54 180)
			(size 1.9304 0.635)
			(layers "F.Cu" "F.Mask" "F.Paste")
			(net "SMB_SENSOR_STBY_LVC3_SCL_R2")
		)
		(pad "7" smd rect
			(at 5.4864 1.27 180)
			(size 1.9304 0.635)
			(layers "F.Cu" "F.Mask" "F.Paste")
			(net "PD_FRU_WP")
		)
		(pad "8" smd rect
			(at 5.4864 0 180)
			(size 1.9304 0.635)
			(layers "F.Cu" "F.Mask" "F.Paste")
			(net "P3V3_STBY")
		)
	)
	(footprint ""
		(layer "F.Cu")
		(at 367.411 -100.076)
		(property "Reference" "Y7C2"
			(at -0.127 -1.49733 0)
			(unlocked yes)
			(layer "F.SilkS")
			(effects
				(font
					(size 0.7874 0.5842)
					(thickness 0.1524)
				)
			)
		)
		(property "Value" ""
			(at 0 0 0)
			(layer "F.Fab")
			(effects
				(font
					(size 1.27 1.27)
				)
			)
		)
		(duplicate_pad_numbers_are_jumpers no)
		(fp_line
			(start -0.8001 1.9558)
			(end -0.8001 1.0922)
			(stroke
				(width 0.1524)
				(type default)
			)
			(layer "F.SilkS")
		)
		(fp_line
			(start 0.8001 1.9558)
			(end 0.8001 1.0922)
			(stroke
				(width 0.1524)
				(type default)
			)
			(layer "F.SilkS")
		)
		(fp_rect
			(start -0.8001 3.173984)
			(end 0.8001 -0.125984)
			(stroke
				(width 0)
				(type default)
			)
			(fill no)
			(layer "F.CrtYd")
		)
		(fp_line
			(start -0.8001 -0.125984)
			(end -0.8001 3.173984)
			(stroke
				(width 0.1)
				(type default)
			)
			(layer "F.Fab")
		)
		(fp_line
			(start -0.8001 3.173984)
			(end 0.8001 3.173984)
			(stroke
				(width 0.1)
				(type default)
			)
			(layer "F.Fab")
		)
		(fp_line
			(start 0.8001 -0.125984)
			(end -0.8001 -0.125984)
			(stroke
				(width 0.1)
				(type default)
			)
			(layer "F.Fab")
		)
		(fp_line
			(start 0.8001 3.173984)
			(end 0.8001 -0.125984)
			(stroke
				(width 0.1)
				(type default)
			)
			(layer "F.Fab")
		)
		(pad "1" smd rect
			(at 0 0)
			(size 1.6002 1.524)
			(layers "F.Cu" "F.Mask" "F.Paste")
			(net "XTAL_33K_RTC1")
		)
		(pad "2" smd rect
			(at 0 3.048)
			(size 1.6002 1.524)
			(layers "F.Cu" "F.Mask" "F.Paste")
			(net "XTAL_33K_RTC2")
		)
	)
	(footprint ""
		(layer "F.Cu")
		(at 355.656388 -139.87399 180)
		(property "Reference" "R7A8"
			(at 0 0 180)
			(layer "F.SilkS")
			(hide yes)
			(effects
				(font
					(size 1.27 1.27)
				)
			)
		)
		(property "Value" ""
			(at 0 0 180)
			(layer "F.Fab")
			(effects
				(font
					(size 1.27 1.27)
				)
			)
		)
		(duplicate_pad_numbers_are_jumpers no)
		(fp_poly
			(pts
				(xy -0.2794 -0.1016) (xy 0.2794 -0.1016) (xy 0.2794 0.9906) (xy -0.2794 0.9906)
			)
			(stroke
				(width 0)
				(type default)
			)
			(fill no)
			(layer "F.CrtYd")
		)
		(fp_line
			(start 0.2794 0.9906)
			(end 0.2794 -0.1016)
			(stroke
				(width 0.1)
				(type default)
			)
			(layer "F.Fab")
		)
		(fp_line
			(start 0.2794 -0.1016)
			(end -0.2794 -0.1016)
			(stroke
				(width 0.1)
				(type default)
			)
			(layer "F.Fab")
		)
		(fp_line
			(start -0.2794 0.9906)
			(end 0.2794 0.9906)
			(stroke
				(width 0.1)
				(type default)
			)
			(layer "F.Fab")
		)
		(fp_line
			(start -0.2794 -0.1016)
			(end -0.2794 0.9906)
			(stroke
				(width 0.1)
				(type default)
			)
			(layer "F.Fab")
		)
		(pad "1" smd rect
			(at 0 0 180)
			(size 0.508 0.508)
			(layers "F.Cu" "F.Mask" "F.Paste")
			(net "VR_PVDDQ_DEF_XADDR2")
		)
		(pad "2" smd rect
			(at 0 0.889 180)
			(size 0.508 0.508)
			(layers "F.Cu" "F.Mask" "F.Paste")
			(net "GND")
		)
		(zone
			(layer "F.Cu")
			(hatch none 0.5)
			(connect_pads
				(clearance 0)
			)
			(min_thickness 0.25)
			(keepout
				(tracks not_allowed)
				(vias allowed)
				(pads allowed)
				(copperpour not_allowed)
				(footprints allowed)
			)
			(placement
				(enabled no)
				(sheetname "")
			)
			(fill
				(thermal_gap 0.5)
				(thermal_bridge_width 0.5)
				(island_removal_mode 0)
			)
			(polygon
				(pts
					(xy 355.910388 -140.50899) (xy 355.402388 -140.50899) (xy 355.402388 -140.12799) (xy 355.910388 -140.12799)
				)
			)
		)
		(zone
			(layer "F.Cu")
			(hatch none 0.5)
			(connect_pads
				(clearance 0)
			)
			(min_thickness 0.25)
			(keepout
				(tracks allowed)
				(vias not_allowed)
				(pads allowed)
				(copperpour not_allowed)
				(footprints allowed)
			)
			(placement
				(enabled no)
				(sheetname "")
			)
			(fill
				(thermal_gap 0.5)
				(thermal_bridge_width 0.5)
				(island_removal_mode 0)
			)
			(polygon
				(pts
					(xy 355.910388 -140.12799) (xy 355.402388 -140.12799) (xy 355.402388 -140.50899) (xy 355.910388 -140.50899)
				)
			)
		)
	)
	(footprint ""
		(layer "F.Cu")
		(at 418.7571 -87.6935 180)
		(property "Reference" "R2P3"
			(at 0 0 180)
			(layer "F.SilkS")
			(hide yes)
			(effects
				(font
					(size 1.27 1.27)
				)
			)
		)
		(property "Value" ""
			(at 0 0 180)
			(layer "F.Fab")
			(effects
				(font
					(size 1.27 1.27)
				)
			)
		)
		(duplicate_pad_numbers_are_jumpers no)
		(fp_poly
			(pts
				(xy -0.2794 -0.1016) (xy 0.2794 -0.1016) (xy 0.2794 0.9906) (xy -0.2794 0.9906)
			)
			(stroke
				(width 0)
				(type default)
			)
			(fill no)
			(layer "F.CrtYd")
		)
		(fp_line
			(start 0.2794 0.9906)
			(end 0.2794 -0.1016)
			(stroke
				(width 0.1)
				(type default)
			)
			(layer "F.Fab")
		)
		(fp_line
			(start 0.2794 -0.1016)
			(end -0.2794 -0.1016)
			(stroke
				(width 0.1)
				(type default)
			)
			(layer "F.Fab")
		)
		(fp_line
			(start -0.2794 0.9906)
			(end 0.2794 0.9906)
			(stroke
				(width 0.1)
				(type default)
			)
			(layer "F.Fab")
		)
		(fp_line
			(start -0.2794 -0.1016)
			(end -0.2794 0.9906)
			(stroke
				(width 0.1)
				(type default)
			)
			(layer "F.Fab")
		)
		(pad "1" smd rect
			(at 0 0 180)
			(size 0.508 0.508)
			(layers "F.Cu" "F.Mask" "F.Paste")
			(net "P3V3_STBY")
		)
		(pad "2" smd rect
			(at 0 0.889 180)
			(size 0.508 0.508)
			(layers "F.Cu" "F.Mask" "F.Paste")
			(net "IRQ_FORCE_NM_THROTTLE_R_N")
		)
		(zone
			(layer "F.Cu")
			(hatch none 0.5)
			(connect_pads
				(clearance 0)
			)
			(min_thickness 0.25)
			(keepout
				(tracks not_allowed)
				(vias allowed)
				(pads allowed)
				(copperpour not_allowed)
				(footprints allowed)
			)
			(placement
				(enabled no)
				(sheetname "")
			)
			(fill
				(thermal_gap 0.5)
				(thermal_bridge_width 0.5)
				(island_removal_mode 0)
			)
			(polygon
				(pts
					(xy 419.0111 -88.3285) (xy 418.5031 -88.3285) (xy 418.5031 -87.9475) (xy 419.0111 -87.9475)
				)
			)
		)
		(zone
			(layer "F.Cu")
			(hatch none 0.5)
			(connect_pads
				(clearance 0)
			)
			(min_thickness 0.25)
			(keepout
				(tracks allowed)
				(vias not_allowed)
				(pads allowed)
				(copperpour not_allowed)
				(footprints allowed)
			)
			(placement
				(enabled no)
				(sheetname "")
			)
			(fill
				(thermal_gap 0.5)
				(thermal_bridge_width 0.5)
				(island_removal_mode 0)
			)
			(polygon
				(pts
					(xy 419.0111 -87.9475) (xy 418.5031 -87.9475) (xy 418.5031 -88.3285) (xy 419.0111 -88.3285)
				)
			)
		)
	)
	(footprint ""
		(layer "F.Cu")
		(at 104.442768 -79.6036 180)
		(property "Reference" "C3W3"
			(at 0.97536 0.76708 90)
			(unlocked yes)
			(layer "F.SilkS")
			(effects
				(font
					(size 0.4064 0.254)
					(thickness 0.1524)
				)
			)
		)
		(property "Value" ""
			(at 0 0 180)
			(layer "F.Fab")
			(effects
				(font
					(size 1.27 1.27)
				)
			)
		)
		(duplicate_pad_numbers_are_jumpers no)
		(fp_poly
			(pts
				(xy -0.4953 -0.2032) (xy 0.4953 -0.2032) (xy 0.4953 1.6002) (xy -0.4953 1.6002)
			)
			(stroke
				(width 0)
				(type default)
			)
			(fill no)
			(layer "F.CrtYd")
		)
		(fp_line
			(start 0.4953 1.6002)
			(end -0.4953 1.6002)
			(stroke
				(width 0.1)
				(type default)
			)
			(layer "F.Fab")
		)
		(fp_line
			(start 0.4953 -0.2032)
			(end 0.4953 1.6002)
			(stroke
				(width 0.1)
				(type default)
			)
			(layer "F.Fab")
		)
		(fp_line
			(start -0.4953 1.6002)
			(end -0.4953 -0.2032)
			(stroke
				(width 0.1)
				(type default)
			)
			(layer "F.Fab")
		)
		(fp_line
			(start -0.4953 -0.2032)
			(end 0.4953 -0.2032)
			(stroke
				(width 0.1)
				(type default)
			)
			(layer "F.Fab")
		)
		(pad "1" smd rect
			(at 0 0 180)
			(size 0.762 0.889)
			(layers "F.Cu" "F.Mask" "F.Paste")
			(net "PVCCMCP_CPU1")
		)
		(pad "2" smd rect
			(at 0 1.397 180)
			(size 0.762 0.889)
			(layers "F.Cu" "F.Mask" "F.Paste")
			(net "GND")
		)
		(zone
			(layer "F.Cu")
			(hatch none 0.5)
			(connect_pads
				(clearance 0)
			)
			(min_thickness 0.25)
			(keepout
				(tracks not_allowed)
				(vias allowed)
				(pads allowed)
				(copperpour not_allowed)
				(footprints allowed)
			)
			(placement
				(enabled no)
				(sheetname "")
			)
			(fill
				(thermal_gap 0.5)
				(thermal_bridge_width 0.5)
				(island_removal_mode 0)
			)
			(polygon
				(pts
					(xy 104.823768 -80.0481) (xy 104.061768 -80.0481) (xy 104.061768 -80.5561) (xy 104.823768 -80.5561)
				)
			)
		)
	)
	(footprint ""
		(layer "F.Cu")
		(at 181.483 -51.5874 90)
		(property "Reference" "C4E15"
			(at 0 0 90)
			(layer "F.SilkS")
			(hide yes)
			(effects
				(font
					(size 1.27 1.27)
				)
			)
		)
		(property "Value" ""
			(at 0 0 90)
			(layer "F.Fab")
			(effects
				(font
					(size 1.27 1.27)
				)
			)
		)
		(duplicate_pad_numbers_are_jumpers no)
		(fp_poly
			(pts
				(xy 0.3048 -0.1016) (xy 0.3048 0.9906) (xy -0.3048 0.9906) (xy -0.3048 -0.1016)
			)
			(stroke
				(width 0)
				(type default)
			)
			(fill no)
			(layer "F.CrtYd")
		)
		(fp_line
			(start 0.3048 -0.1016)
			(end -0.3048 -0.1016)
			(stroke
				(width 0.1)
				(type default)
			)
			(layer "F.Fab")
		)
		(fp_line
			(start -0.3048 -0.1016)
			(end -0.3048 0.9906)
			(stroke
				(width 0.1)
				(type default)
			)
			(layer "F.Fab")
		)
		(fp_line
			(start 0.3048 0.9906)
			(end 0.3048 -0.1016)
			(stroke
				(width 0.1)
				(type default)
			)
			(layer "F.Fab")
		)
		(fp_line
			(start -0.3048 0.9906)
			(end 0.3048 0.9906)
			(stroke
				(width 0.1)
				(type default)
			)
			(layer "F.Fab")
		)
		(pad "1" smd rect
			(at 0 0 90)
			(size 0.508 0.508)
			(layers "F.Cu" "F.Mask" "F.Paste")
			(net "VR_FET_SW_P12V_STBY_PVCCIN_CPU0")
		)
		(pad "2" smd rect
			(at 0 0.889 90)
			(size 0.508 0.508)
			(layers "F.Cu" "F.Mask" "F.Paste")
			(net "GND")
		)
		(zone
			(layer "F.Cu")
			(hatch none 0.5)
			(connect_pads
				(clearance 0)
			)
			(min_thickness 0.25)
			(keepout
				(tracks allowed)
				(vias not_allowed)
				(pads allowed)
				(copperpour not_allowed)
				(footprints allowed)
			)
			(placement
				(enabled no)
				(sheetname "")
			)
			(fill
				(thermal_gap 0.5)
				(thermal_bridge_width 0.5)
				(island_removal_mode 0)
			)
			(polygon
				(pts
					(xy 181.737 -51.3334) (xy 181.737 -51.8414) (xy 182.118 -51.8414) (xy 182.118 -51.3334)
				)
			)
		)
		(zone
			(layer "F.Cu")
			(hatch none 0.5)
			(connect_pads
				(clearance 0)
			)
			(min_thickness 0.25)
			(keepout
				(tracks not_allowed)
				(vias allowed)
				(pads allowed)
				(copperpour not_allowed)
				(footprints allowed)
			)
			(placement
				(enabled no)
				(sheetname "")
			)
			(fill
				(thermal_gap 0.5)
				(thermal_bridge_width 0.5)
				(island_removal_mode 0)
			)
			(polygon
				(pts
					(xy 182.118 -51.3334) (xy 182.118 -51.8414) (xy 181.737 -51.8414) (xy 181.737 -51.3334)
				)
			)
		)
	)
)
